(kicad_pcb
	(version 20241229)
	(generator "pcbnew")
	(generator_version "9.0")
	(general
		(thickness 1.63)
		(legacy_teardrops no)
	)
	(paper "A4")
	(title_block
		(title "CM4 Baseboard")
		(date "2026-01-05")
		(rev "1.1.1")
		(company "Antmicro Ltd")
		(comment 1 "www.antmicro.com")
		(comment 9 "footprints 427-430 of 506")
	)
	(layers
		(0 "F.Cu" signal)
		(4 "In1.Cu" power)
		(6 "In2.Cu" power)
		(8 "In3.Cu" signal)
		(10 "In4.Cu" signal)
		(2 "B.Cu" signal)
		(9 "F.Adhes" user "F.Adhesive")
		(11 "B.Adhes" user "B.Adhesive")
		(13 "F.Paste" user)
		(15 "B.Paste" user)
		(5 "F.SilkS" user "F.Silkscreen")
		(7 "B.SilkS" user "B.Silkscreen")
		(1 "F.Mask" user)
		(3 "B.Mask" user)
		(17 "Dwgs.User" user "User.Drawings")
		(19 "Cmts.User" user "User.Comments")
		(21 "Eco1.User" user "User.Eco1")
		(23 "Eco2.User" user "User.Eco2")
		(25 "Edge.Cuts" user)
		(27 "Margin" user)
		(31 "F.CrtYd" user "F.Courtyard")
		(29 "B.CrtYd" user "B.Courtyard")
		(35 "F.Fab" user)
		(33 "B.Fab" user)
	)
	(footprint "antmicro-footprints:C_0402_1005Metric"
		(layer "B.Cu")
		(at 66.417962 133.9165)
		(descr "Capacitor SMD 0402")
		(tags "capacitor SMD 0402")
		(property "Reference" "C402"
			(at -1.33 1.55 0)
			(layer "B.SilkS")
			(effects
				(font
					(size 0.7 0.7)
					(thickness 0.15)
				)
				(justify right bottom mirror)
			)
		)
		(property "Value" "C_10n_0402"
			(at -1.022927 -2.155213 0)
			(layer "B.Fab")
			(effects
				(font
					(size 0.7 0.7)
					(thickness 0.15)
				)
				(justify right bottom mirror)
			)
		)
		(property "Datasheet" "https://www.murata.com/products/productdetail?partno=GRM155R71H103KA88%23"
			(at 0 0 0)
			(layer "B.Fab")
			(hide yes)
			(effects
				(font
					(size 1.27 1.27)
					(thickness 0.15)
				)
			)
		)
		(property "Manufacturer" "Murata"
			(at 0 0 0)
			(unlocked yes)
			(layer "B.Fab")
			(hide yes)
			(effects
				(font
					(size 1 1)
					(thickness 0.15)
				)
				(justify mirror)
			)
		)
		(property "MPN" "GRM155R71H103KA88D"
			(at 0 0 0)
			(unlocked yes)
			(layer "B.Fab")
			(hide yes)
			(effects
				(font
					(size 1 1)
					(thickness 0.15)
				)
				(justify mirror)
			)
		)
		(property "Val" "10n"
			(at 0 0 0)
			(unlocked yes)
			(layer "B.Fab")
			(hide yes)
			(effects
				(font
					(size 1 1)
					(thickness 0.15)
				)
				(justify mirror)
			)
		)
		(property "License" "Apache-2.0"
			(at 0 0 0)
			(unlocked yes)
			(layer "B.Fab")
			(hide yes)
			(effects
				(font
					(size 1 1)
					(thickness 0.15)
				)
				(justify mirror)
			)
		)
		(property "Author" "Antmicro"
			(at 0 0 0)
			(unlocked yes)
			(layer "B.Fab")
			(hide yes)
			(effects
				(font
					(size 1 1)
					(thickness 0.15)
				)
				(justify mirror)
			)
		)
		(property "Voltage" "50V"
			(at 0 0 0)
			(unlocked yes)
			(layer "B.Fab")
			(hide yes)
			(effects
				(font
					(size 1 1)
					(thickness 0.15)
				)
				(justify mirror)
			)
		)
		(property "Dielectric" "X7R"
			(at 0 0 0)
			(unlocked yes)
			(layer "B.Fab")
			(hide yes)
			(effects
				(font
					(size 1 1)
					(thickness 0.15)
				)
				(justify mirror)
			)
		)
		(sheetname "/Ethernet/")
		(sheetfile "ethernet.kicad_sch")
		(attr smd)
		(fp_rect
			(start -0.925 0.47)
			(end 0.925 -0.47)
			(stroke
				(width 0.05)
				(type default)
			)
			(fill no)
			(layer "B.CrtYd")
		)
		(fp_line
			(start -0.494 -0.248)
			(end -0.494 0.25)
			(stroke
				(width 0.15)
				(type solid)
			)
			(layer "B.Fab")
		)
		(fp_line
			(start -0.494 0.25)
			(end 0.504 0.25)
			(stroke
				(width 0.15)
				(type solid)
			)
			(layer "B.Fab")
		)
		(fp_line
			(start 0.504 -0.248)
			(end -0.494 -0.248)
			(stroke
				(width 0.15)
				(type solid)
			)
			(layer "B.Fab")
		)
		(fp_line
			(start 0.504 0.25)
			(end 0.504 -0.248)
			(stroke
				(width 0.15)
				(type solid)
			)
			(layer "B.Fab")
		)
		(fp_text user "Author: Antmicro"
			(at -0.939 -3.399 180)
			(layer "B.Fab")
			(effects
				(font
					(size 0.7 0.7)
					(thickness 0.15)
				)
				(justify left bottom mirror)
			)
		)
		(fp_text user "${REFERENCE}"
			(at -0.939 -4.599 180)
			(layer "B.Fab")
			(effects
				(font
					(size 0.7 0.7)
					(thickness 0.15)
				)
				(justify left bottom mirror)
			)
		)
		(fp_text user "License: Apache-2.0"
			(at -0.939 -5.799 180)
			(layer "B.Fab")
			(effects
				(font
					(size 0.7 0.7)
					(thickness 0.15)
				)
				(justify left bottom mirror)
			)
		)
		(pad "1" smd roundrect
			(at -0.48 0)
			(size 0.59 0.64)
			(layers "B.Cu" "B.Mask" "B.Paste")
			(roundrect_rratio 0.25)
			(net 91 "Net-(J401-P4)")
			(pintype "passive")
		)
		(pad "2" smd roundrect
			(at 0.48 0)
			(size 0.59 0.64)
			(layers "B.Cu" "B.Mask" "B.Paste")
			(roundrect_rratio 0.25)
			(net 3 "GND")
			(pintype "passive")
		)
	)
	(footprint "antmicro-footprints:R_0402_1005Metric"
		(layer "B.Cu")
		(at 126.4 170 180)
		(descr "Resistor SMD 0402")
		(tags "resistor SMD 0402")
		(property "Reference" "R513"
			(at 1.01 -0.435 0)
			(layer "B.SilkS")
			(effects
				(font
					(size 0.7 0.7)
					(thickness 0.15)
				)
				(justify left bottom mirror)
			)
		)
		(property "Value" "R_10k_0402"
			(at -1.011843 -1.772047 0)
			(layer "B.Fab")
			(effects
				(font
					(size 0.7 0.7)
					(thickness 0.15)
				)
				(justify left bottom mirror)
			)
		)
		(property "Datasheet" "https://www.bourns.com/docs/product-datasheets/cr.pdf"
			(at 0 0 180)
			(layer "B.Fab")
			(hide yes)
			(effects
				(font
					(size 1.27 1.27)
					(thickness 0.15)
				)
			)
		)
		(property "Manufacturer" "Bourns"
			(at 0 0 180)
			(unlocked yes)
			(layer "B.Fab")
			(hide yes)
			(effects
				(font
					(size 1 1)
					(thickness 0.15)
				)
				(justify mirror)
			)
		)
		(property "MPN" "CR0402-FX-1002GLF"
			(at 0 0 180)
			(unlocked yes)
			(layer "B.Fab")
			(hide yes)
			(effects
				(font
					(size 1 1)
					(thickness 0.15)
				)
				(justify mirror)
			)
		)
		(property "Val" "10k"
			(at 0 0 180)
			(unlocked yes)
			(layer "B.Fab")
			(hide yes)
			(effects
				(font
					(size 1 1)
					(thickness 0.15)
				)
				(justify mirror)
			)
		)
		(property "License" "Apache-2.0"
			(at 0 0 180)
			(unlocked yes)
			(layer "B.Fab")
			(hide yes)
			(effects
				(font
					(size 1 1)
					(thickness 0.15)
				)
				(justify mirror)
			)
		)
		(property "Author" "Antmicro"
			(at 0 0 180)
			(unlocked yes)
			(layer "B.Fab")
			(hide yes)
			(effects
				(font
					(size 1 1)
					(thickness 0.15)
				)
				(justify mirror)
			)
		)
		(property "Tolerance" "1%"
			(at 0 0 180)
			(unlocked yes)
			(layer "B.Fab")
			(hide yes)
			(effects
				(font
					(size 1 1)
					(thickness 0.15)
				)
				(justify mirror)
			)
		)
		(sheetname "/NVMe & microSD/")
		(sheetfile "nvme-micro-sd.kicad_sch")
		(attr smd)
		(fp_rect
			(start -0.925 0.47)
			(end 0.925 -0.47)
			(stroke
				(width 0.05)
				(type default)
			)
			(fill no)
			(layer "B.CrtYd")
		)
		(fp_rect
			(start -0.5 0.25)
			(end 0.5 -0.25)
			(stroke
				(width 0.15)
				(type solid)
			)
			(fill no)
			(layer "B.Fab")
		)
		(fp_text user "${REFERENCE}"
			(at -0.95 -3.168 0)
			(layer "B.Fab")
			(effects
				(font
					(size 0.7 0.7)
					(thickness 0.15)
				)
				(justify left bottom mirror)
			)
		)
		(fp_text user "Author: Antmicro"
			(at -0.95 -4.169 0)
			(layer "B.Fab")
			(effects
				(font
					(size 0.7 0.7)
					(thickness 0.15)
				)
				(justify left bottom mirror)
			)
		)
		(fp_text user "License: Apache-2.0"
			(at -0.95 -5.169 0)
			(layer "B.Fab")
			(effects
				(font
					(size 0.7 0.7)
					(thickness 0.15)
				)
				(justify left bottom mirror)
			)
		)
		(pad "1" smd roundrect
			(at -0.48 0 180)
			(size 0.59 0.64)
			(layers "B.Cu" "B.Mask" "B.Paste")
			(roundrect_rratio 0.25)
			(net 263 "Net-(J502-CD2)")
			(pintype "passive")
		)
		(pad "2" smd roundrect
			(at 0.48 0 180)
			(size 0.59 0.64)
			(layers "B.Cu" "B.Mask" "B.Paste")
			(roundrect_rratio 0.25)
			(net 3 "GND")
			(pintype "passive")
		)
	)
	(footprint "antmicro-footprints:C_0402_1005Metric"
		(layer "B.Cu")
		(at 56.167962 155.3165 90)
		(descr "Capacitor SMD 0402")
		(tags "capacitor SMD 0402")
		(property "Reference" "C310"
			(at 1.505 3.17 90)
			(layer "B.SilkS")
			(effects
				(font
					(size 0.7 0.7)
					(thickness 0.15)
				)
				(justify right bottom mirror)
			)
		)
		(property "Value" "C_100n_0402"
			(at -1.022927 -2.155213 90)
			(layer "B.Fab")
			(effects
				(font
					(size 0.7 0.7)
					(thickness 0.15)
				)
				(justify right bottom mirror)
			)
		)
		(property "Datasheet" "https://www.murata.com/products/productdetail?partno=GRM155R61H104KE14%23"
			(at 0 0 90)
			(layer "B.Fab")
			(hide yes)
			(effects
				(font
					(size 1.27 1.27)
					(thickness 0.15)
				)
			)
		)
		(property "Manufacturer" "Murata"
			(at 0 0 90)
			(unlocked yes)
			(layer "B.Fab")
			(hide yes)
			(effects
				(font
					(size 1 1)
					(thickness 0.15)
				)
				(justify mirror)
			)
		)
		(property "MPN" "GRM155R61H104KE14D"
			(at 0 0 90)
			(unlocked yes)
			(layer "B.Fab")
			(hide yes)
			(effects
				(font
					(size 1 1)
					(thickness 0.15)
				)
				(justify mirror)
			)
		)
		(property "Val" "100n"
			(at 0 0 90)
			(unlocked yes)
			(layer "B.Fab")
			(hide yes)
			(effects
				(font
					(size 1 1)
					(thickness 0.15)
				)
				(justify mirror)
			)
		)
		(property "License" "Apache-2.0"
			(at 0 0 90)
			(unlocked yes)
			(layer "B.Fab")
			(hide yes)
			(effects
				(font
					(size 1 1)
					(thickness 0.15)
				)
				(justify mirror)
			)
		)
		(property "Author" "Antmicro"
			(at 0 0 90)
			(unlocked yes)
			(layer "B.Fab")
			(hide yes)
			(effects
				(font
					(size 1 1)
					(thickness 0.15)
				)
				(justify mirror)
			)
		)
		(property "Voltage" "50V"
			(at 0 0 90)
			(unlocked yes)
			(layer "B.Fab")
			(hide yes)
			(effects
				(font
					(size 1 1)
					(thickness 0.15)
				)
				(justify mirror)
			)
		)
		(property "Dielectric" "X5R"
			(at 0 0 90)
			(unlocked yes)
			(layer "B.Fab")
			(hide yes)
			(effects
				(font
					(size 1 1)
					(thickness 0.15)
				)
				(justify mirror)
			)
		)
		(sheetname "/Supply/")
		(sheetfile "supply.kicad_sch")
		(attr smd)
		(fp_rect
			(start -0.925 0.47)
			(end 0.925 -0.47)
			(stroke
				(width 0.05)
				(type default)
			)
			(fill no)
			(layer "B.CrtYd")
		)
		(fp_line
			(start 0.504 -0.248)
			(end -0.494 -0.248)
			(stroke
				(width 0.15)
				(type solid)
			)
			(layer "B.Fab")
		)
		(fp_line
			(start -0.494 -0.248)
			(end -0.494 0.25)
			(stroke
				(width 0.15)
				(type solid)
			)
			(layer "B.Fab")
		)
		(fp_line
			(start 0.504 0.25)
			(end 0.504 -0.248)
			(stroke
				(width 0.15)
				(type solid)
			)
			(layer "B.Fab")
		)
		(fp_line
			(start -0.494 0.25)
			(end 0.504 0.25)
			(stroke
				(width 0.15)
				(type solid)
			)
			(layer "B.Fab")
		)
		(fp_text user "License: Apache-2.0"
			(at -0.939 -5.799 270)
			(layer "B.Fab")
			(effects
				(font
					(size 0.7 0.7)
					(thickness 0.15)
				)
				(justify left bottom mirror)
			)
		)
		(fp_text user "${REFERENCE}"
			(at -0.939 -4.599 270)
			(layer "B.Fab")
			(effects
				(font
					(size 0.7 0.7)
					(thickness 0.15)
				)
				(justify left bottom mirror)
			)
		)
		(fp_text user "Author: Antmicro"
			(at -0.939 -3.399 270)
			(layer "B.Fab")
			(effects
				(font
					(size 0.7 0.7)
					(thickness 0.15)
				)
				(justify left bottom mirror)
			)
		)
		(pad "1" smd roundrect
			(at -0.48 0 90)
			(size 0.59 0.64)
			(layers "B.Cu" "B.Mask" "B.Paste")
			(roundrect_rratio 0.25)
			(net 59 "/Supply/SW_5V")
			(pintype "passive")
		)
		(pad "2" smd roundrect
			(at 0.48 0 90)
			(size 0.59 0.64)
			(layers "B.Cu" "B.Mask" "B.Paste")
			(roundrect_rratio 0.25)
			(net 60 "Net-(U303-BST)")
			(pintype "passive")
		)
	)
	(footprint "antmicro-footprints:Nexperia_DFN-10_2.5x1mm_P0.5mm"
		(layer "B.Cu")
		(at 101.080962 172.6785 90)
		(property "Reference" "D704"
			(at -0.608 2.597 90)
			(layer "B.SilkS")
			(effects
				(font
					(size 0.7 0.7)
					(thickness 0.15)
				)
				(justify right bottom mirror)
			)
		)
		(property "Value" "PUSB3F96X_PASS"
			(at -0.016 -1.705 90)
			(layer "B.Fab")
			(effects
				(font
					(size 0.7 0.7)
					(thickness 0.15)
				)
				(justify right bottom mirror)
			)
		)
		(property "Datasheet" "https://mouser.com/datasheet/2/916/PUSB3F96-1600324.pdf"
			(at 0 0 90)
			(layer "B.Fab")
			(hide yes)
			(effects
				(font
					(size 1.27 1.27)
					(thickness 0.15)
				)
			)
		)
		(property "Manufacturer" "Nexperia"
			(at 0 0 90)
			(unlocked yes)
			(layer "B.Fab")
			(hide yes)
			(effects
				(font
					(size 1 1)
					(thickness 0.15)
				)
				(justify mirror)
			)
		)
		(property "MPN" "PUSB3F96X"
			(at 0 0 90)
			(unlocked yes)
			(layer "B.Fab")
			(hide yes)
			(effects
				(font
					(size 1 1)
					(thickness 0.15)
				)
				(justify mirror)
			)
		)
		(property "Author" "Antmicro"
			(at 0 0 90)
			(unlocked yes)
			(layer "B.Fab")
			(hide yes)
			(effects
				(font
					(size 1 1)
					(thickness 0.15)
				)
				(justify mirror)
			)
		)
		(property "License" "Apache-2.0"
			(at 0 0 90)
			(unlocked yes)
			(layer "B.Fab")
			(hide yes)
			(effects
				(font
					(size 1 1)
					(thickness 0.15)
				)
				(justify mirror)
			)
		)
		(sheetname "/Display/")
		(sheetfile "display.kicad_sch")
		(attr smd)
		(fp_line
			(start 1.375 -0.4)
			(end 1.375 0.4)
			(stroke
				(width 0.15)
				(type solid)
			)
			(layer "B.SilkS")
		)
		(fp_line
			(start -1.375 0.4)
			(end -1.375 -0.4)
			(stroke
				(width 0.15)
				(type solid)
			)
			(layer "B.SilkS")
		)
		(fp_circle
			(center -1.4 -0.7)
			(end -1.349 -0.7)
			(stroke
				(width 0.15)
				(type solid)
			)
			(fill yes)
			(layer "B.SilkS")
		)
		(fp_rect
			(start -1.4 0.725)
			(end 1.4 -0.725)
			(stroke
				(width 0.05)
				(type solid)
			)
			(fill no)
			(layer "B.CrtYd")
		)
		(fp_line
			(start 1.25 -0.5)
			(end 1.25 0.5)
			(stroke
				(width 0.15)
				(type solid)
			)
			(layer "B.Fab")
		)
		(fp_line
			(start -0.9 -0.5)
			(end 1.25 -0.5)
			(stroke
				(width 0.15)
				(type solid)
			)
			(layer "B.Fab")
		)
		(fp_line
			(start -1.25 -0.15)
			(end -0.9 -0.5)
			(stroke
				(width 0.15)
				(type solid)
			)
			(layer "B.Fab")
		)
		(fp_line
			(start 1.25 0.5)
			(end -1.25 0.5)
			(stroke
				(width 0.15)
				(type solid)
			)
			(layer "B.Fab")
		)
		(fp_line
			(start -1.25 0.5)
			(end -1.25 -0.15)
			(stroke
				(width 0.15)
				(type solid)
			)
			(layer "B.Fab")
		)
		(fp_text user "${REFERENCE}"
			(at -1.367 -3.704 270)
			(layer "B.Fab")
			(effects
				(font
					(size 0.7 0.7)
					(thickness 0.15)
				)
				(justify left bottom mirror)
			)
		)
		(fp_text user "Author: Antmicro"
			(at -1.367 -4.905 270)
			(layer "B.Fab")
			(effects
				(font
					(size 0.7 0.7)
					(thickness 0.15)
				)
				(justify left bottom mirror)
			)
		)
		(fp_text user "License: Apache-2.0"
			(at -1.367 -6.105 270)
			(layer "B.Fab")
			(effects
				(font
					(size 0.7 0.7)
					(thickness 0.15)
				)
				(justify left bottom mirror)
			)
		)
		(pad "1" smd rect
			(at -1 -0.3875 90)
			(size 0.2 0.475)
			(layers "B.Cu" "B.Mask" "B.Paste")
			(net 143 "/CSI/I_{2}C1.SDA")
			(pinfunction "CH1")
			(pintype "passive")
			(solder_mask_margin 0.05)
		)
		(pad "2" smd rect
			(at -0.5 -0.3875 90)
			(size 0.2 0.475)
			(layers "B.Cu" "B.Mask" "B.Paste")
			(net 142 "/CSI/I_{2}C1.SCL")
			(pinfunction "CH2")
			(pintype "passive")
			(solder_mask_margin 0.05)
		)
		(pad "3" smd rect
			(at 0 -0.3875 90)
			(size 0.2 0.475)
			(layers "B.Cu" "B.Mask" "B.Paste")
			(net 3 "GND")
			(pinfunction "GND")
			(pintype "passive")
			(solder_mask_margin 0.05)
		)
		(pad "4" smd rect
			(at 0.5 -0.3875 90)
			(size 0.2 0.475)
			(layers "B.Cu" "B.Mask" "B.Paste")
			(net 120 "/Compute module/DSICtrl.IRQ1")
			(pinfunction "CH3")
			(pintype "passive")
			(solder_mask_margin 0.05)
		)
		(pad "5" smd rect
			(at 1 -0.3875 90)
			(size 0.2 0.475)
			(layers "B.Cu" "B.Mask" "B.Paste")
			(net 121 "/Compute module/DSICtrl.~{IRQ2}")
			(pinfunction "CH4")
			(pintype "passive")
			(solder_mask_margin 0.05)
		)
		(pad "6" smd rect
			(at 1 0.3875 90)
			(size 0.2 0.475)
			(layers "B.Cu" "B.Mask" "B.Paste")
			(net 121 "/Compute module/DSICtrl.~{IRQ2}")
			(pinfunction "CH4")
			(pintype "passive")
			(solder_mask_margin 0.05)
		)
		(pad "7" smd rect
			(at 0.5 0.3875 90)
			(size 0.2 0.475)
			(layers "B.Cu" "B.Mask" "B.Paste")
			(net 120 "/Compute module/DSICtrl.IRQ1")
			(pinfunction "CH3")
			(pintype "passive")
			(solder_mask_margin 0.05)
		)
		(pad "8" smd rect
			(at 0 0.3875 90)
			(size 0.2 0.475)
			(layers "B.Cu" "B.Mask" "B.Paste")
			(net 3 "GND")
			(pinfunction "GND")
			(pintype "passive")
			(solder_mask_margin 0.05)
		)
		(pad "9" smd rect
			(at -0.501 0.3875 90)
			(size 0.2 0.475)
			(layers "B.Cu" "B.Mask" "B.Paste")
			(net 142 "/CSI/I_{2}C1.SCL")
			(pinfunction "CH2")
			(pintype "passive")
			(solder_mask_margin 0.05)
		)
		(pad "10" smd rect
			(at -1 0.3875 90)
			(size 0.2 0.475)
			(layers "B.Cu" "B.Mask" "B.Paste")
			(net 143 "/CSI/I_{2}C1.SDA")
			(pinfunction "CH1")
			(pintype "passive")
			(solder_mask_margin 0.05)
		)
	)
)
